(kicad_pcb
	(version 20260206)
	(generator "pcbnew")
	(generator_version "10.0")
	(general
		(thickness 1.6)
		(legacy_teardrops no)
	)
	(paper "A4")
	(title_block
		(title "12092022_DA0F0TMDCD0_F0T_Management_Board_D_brd_V3_OCP.brd")
		(comment 1 "Grand Teton / footprints 933-938 of 1440")
	)
	(layers
		(0 "F.Cu" signal "TOP")
		(4 "In1.Cu" signal "GND")
		(6 "In2.Cu" signal "IN1")
		(8 "In3.Cu" signal "GND1")
		(10 "In4.Cu" signal "IN2")
		(12 "In5.Cu" signal "VCC")
		(14 "In6.Cu" signal "VCC1")
		(16 "In7.Cu" signal "IN3")
		(18 "In8.Cu" signal "GND2")
		(20 "In9.Cu" signal "IN4")
		(22 "In10.Cu" signal "GND3")
		(2 "B.Cu" signal "BOTTOM")
		(9 "F.Adhes" user "F.Adhesive")
		(11 "B.Adhes" user "B.Adhesive")
		(13 "F.Paste" user "Package Geometry/Pastemask Top")
		(15 "B.Paste" user "Package Geometry/Pastemask Bottom")
		(5 "F.SilkS" user "Ref Des/Silkscreen Top")
		(7 "B.SilkS" user "Ref Des/Silkscreen Bottom")
		(1 "F.Mask" user "Board Geometry/Soldermask Top")
		(3 "B.Mask" user "Board Geometry/Soldermask Bottom")
		(17 "Dwgs.User" user "User.Drawings")
		(19 "Cmts.User" user "User.Comments")
		(21 "Eco1.User" user "User.Eco1")
		(23 "Eco2.User" user "User.Eco2")
		(25 "Edge.Cuts" user "Board Geometry/Outline")
		(27 "Margin" user)
		(31 "F.CrtYd" user "Package Geometry/Place Bound Top")
		(29 "B.CrtYd" user "Package Geometry/Place Bound Bottom")
		(35 "F.Fab" user "Ref Des/Assembly Top")
		(33 "B.Fab" user "Ref Des/Assembly Bottom")
	)
	(footprint ""
		(layer "B.Cu")
		(at 15.748 -100.711 135)
		(property "Reference" "C163"
			(at 0 0 135)
			(layer "B.SilkS")
			(hide yes)
			(effects
				(font
					(size 1.27 1.27)
				)
				(justify mirror)
			)
		)
		(property "Value" ""
			(at 0 0 135)
			(layer "B.Fab")
			(effects
				(font
					(size 1.27 1.27)
				)
				(justify mirror)
			)
		)
		(duplicate_pad_numbers_are_jumpers no)
		(fp_line
			(start 1.295492 -0.584255)
			(end -1.295492 -0.584255)
			(stroke
				(width 0.1524)
				(type default)
			)
			(layer "B.SilkS")
		)
		(fp_line
			(start 1.295492 0.584255)
			(end 1.295492 -0.584255)
			(stroke
				(width 0.1524)
				(type default)
			)
			(layer "B.SilkS")
		)
		(fp_line
			(start 0 -0.584076)
			(end 0 0.584076)
			(stroke
				(width 0.1524)
				(type default)
			)
			(layer "B.SilkS")
		)
		(fp_line
			(start -1.295492 -0.584255)
			(end -1.295492 0.584255)
			(stroke
				(width 0.1524)
				(type default)
			)
			(layer "B.SilkS")
		)
		(fp_line
			(start -1.295492 0.584255)
			(end 1.295492 0.584255)
			(stroke
				(width 0.1524)
				(type default)
			)
			(layer "B.SilkS")
		)
		(fp_line
			(start 1.193835 -0.406446)
			(end 0.863721 -0.406446)
			(stroke
				(width 0.1)
				(type default)
			)
			(layer "B.Fab")
		)
		(fp_line
			(start 0.863541 -0.457275)
			(end -0.863541 -0.457275)
			(stroke
				(width 0.1)
				(type default)
			)
			(layer "B.Fab")
		)
		(fp_line
			(start 0.863721 -0.406446)
			(end 0.863541 -0.457275)
			(stroke
				(width 0.1)
				(type default)
			)
			(layer "B.Fab")
		)
		(fp_line
			(start 1.193835 0.406446)
			(end 1.193835 -0.406446)
			(stroke
				(width 0.1)
				(type default)
			)
			(layer "B.Fab")
		)
		(fp_line
			(start 0.863721 0.406446)
			(end 1.193835 0.406446)
			(stroke
				(width 0.1)
				(type default)
			)
			(layer "B.Fab")
		)
		(fp_line
			(start 0.863541 0.457275)
			(end 0.863721 0.406446)
			(stroke
				(width 0.1)
				(type default)
			)
			(layer "B.Fab")
		)
		(fp_line
			(start -0.863541 -0.457275)
			(end -0.863721 -0.406446)
			(stroke
				(width 0.1)
				(type default)
			)
			(layer "B.Fab")
		)
		(fp_line
			(start -0.863721 -0.406446)
			(end -1.193835 -0.406446)
			(stroke
				(width 0.1)
				(type default)
			)
			(layer "B.Fab")
		)
		(fp_line
			(start -1.193835 -0.406446)
			(end -1.193835 0.406446)
			(stroke
				(width 0.1)
				(type default)
			)
			(layer "B.Fab")
		)
		(fp_line
			(start -0.863721 0.406446)
			(end -0.863541 0.457275)
			(stroke
				(width 0.1)
				(type default)
			)
			(layer "B.Fab")
		)
		(fp_line
			(start -0.863541 0.457275)
			(end 0.863541 0.457275)
			(stroke
				(width 0.1)
				(type default)
			)
			(layer "B.Fab")
		)
		(fp_line
			(start -1.193835 0.406446)
			(end -0.863721 0.406446)
			(stroke
				(width 0.1)
				(type default)
			)
			(layer "B.Fab")
		)
		(pad "1" smd rect
			(at 0.7366 0 45)
			(size 0.7112 0.8128)
			(layers "B.Cu" "B.Mask" "B.Paste")
			(net "PVCCA_AUX_PLD")
		)
		(pad "2" smd rect
			(at -0.7366 0 45)
			(size 0.7112 0.8128)
			(layers "B.Cu" "B.Mask" "B.Paste")
			(net "GND")
		)
	)
	(footprint ""
		(layer "B.Cu")
		(at 34.8488 -63.6778)
		(property "Reference" "R618"
			(at 0 0 0)
			(layer "B.SilkS")
			(hide yes)
			(effects
				(font
					(size 1.27 1.27)
				)
				(justify mirror)
			)
		)
		(property "Value" ""
			(at 0 0 0)
			(layer "B.Fab")
			(effects
				(font
					(size 1.27 1.27)
				)
				(justify mirror)
			)
		)
		(duplicate_pad_numbers_are_jumpers no)
		(fp_line
			(start -0.7874 -0.4064)
			(end -0.7874 0.4064)
			(stroke
				(width 0.1524)
				(type default)
			)
			(layer "B.SilkS")
		)
		(fp_line
			(start -0.7874 0.4064)
			(end 0.7874 0.4064)
			(stroke
				(width 0.1524)
				(type default)
			)
			(layer "B.SilkS")
		)
		(fp_line
			(start 0.7874 -0.4064)
			(end -0.7874 -0.4064)
			(stroke
				(width 0.1524)
				(type default)
			)
			(layer "B.SilkS")
		)
		(fp_line
			(start 0.7874 0.4064)
			(end 0.7874 -0.4064)
			(stroke
				(width 0.1524)
				(type default)
			)
			(layer "B.SilkS")
		)
		(fp_line
			(start -0.67945 -0.3048)
			(end -0.67945 0.3048)
			(stroke
				(width 0.1)
				(type default)
			)
			(layer "B.Fab")
		)
		(fp_line
			(start -0.67945 0.3048)
			(end -0.120396 0.3048)
			(stroke
				(width 0.1)
				(type default)
			)
			(layer "B.Fab")
		)
		(fp_line
			(start -0.12065 -0.3048)
			(end -0.67945 -0.3048)
			(stroke
				(width 0.1)
				(type default)
			)
			(layer "B.Fab")
		)
		(fp_line
			(start -0.12065 -0.2794)
			(end -0.12065 -0.3048)
			(stroke
				(width 0.1)
				(type default)
			)
			(layer "B.Fab")
		)
		(fp_line
			(start -0.120396 0.2794)
			(end 0.12065 0.2794)
			(stroke
				(width 0.1)
				(type default)
			)
			(layer "B.Fab")
		)
		(fp_line
			(start -0.120396 0.3048)
			(end -0.120396 0.2794)
			(stroke
				(width 0.1)
				(type default)
			)
			(layer "B.Fab")
		)
		(fp_line
			(start 0.12065 -0.305054)
			(end 0.12065 -0.2794)
			(stroke
				(width 0.1)
				(type default)
			)
			(layer "B.Fab")
		)
		(fp_line
			(start 0.12065 -0.2794)
			(end -0.12065 -0.2794)
			(stroke
				(width 0.1)
				(type default)
			)
			(layer "B.Fab")
		)
		(fp_line
			(start 0.12065 0.2794)
			(end 0.12065 0.3048)
			(stroke
				(width 0.1)
				(type default)
			)
			(layer "B.Fab")
		)
		(fp_line
			(start 0.12065 0.3048)
			(end 0.67945 0.3048)
			(stroke
				(width 0.1)
				(type default)
			)
			(layer "B.Fab")
		)
		(fp_line
			(start 0.67945 -0.305054)
			(end 0.12065 -0.305054)
			(stroke
				(width 0.1)
				(type default)
			)
			(layer "B.Fab")
		)
		(fp_line
			(start 0.67945 0.3048)
			(end 0.67945 -0.305054)
			(stroke
				(width 0.1)
				(type default)
			)
			(layer "B.Fab")
		)
		(pad "1" smd circle
			(at 0.40005 0 180)
			(size 0 0)
			(layers "B.Cu" "B.Mask" "B.Paste")
			(net "UART_SYS_DBG_RX")
		)
		(pad "2" smd circle
			(at -0.40005 0 180)
			(size 0 0)
			(layers "B.Cu" "B.Mask" "B.Paste")
			(net "UART_SYS_DBG_RX_R")
		)
	)
	(footprint ""
		(layer "B.Cu")
		(at 55.123334 -54.87162)
		(property "Reference" "C106"
			(at 0 0 0)
			(layer "B.SilkS")
			(hide yes)
			(effects
				(font
					(size 1.27 1.27)
				)
				(justify mirror)
			)
		)
		(property "Value" ""
			(at 0 0 0)
			(layer "B.Fab")
			(effects
				(font
					(size 1.27 1.27)
				)
				(justify mirror)
			)
		)
		(duplicate_pad_numbers_are_jumpers no)
		(fp_line
			(start -0.7874 -0.4064)
			(end -0.7874 0.4064)
			(stroke
				(width 0.1524)
				(type default)
			)
			(layer "B.SilkS")
		)
		(fp_line
			(start -0.7874 0.4064)
			(end 0.7874 0.4064)
			(stroke
				(width 0.1524)
				(type default)
			)
			(layer "B.SilkS")
		)
		(fp_line
			(start 0.7874 -0.4064)
			(end -0.7874 -0.4064)
			(stroke
				(width 0.1524)
				(type default)
			)
			(layer "B.SilkS")
		)
		(fp_line
			(start 0.7874 0.4064)
			(end 0.7874 -0.4064)
			(stroke
				(width 0.1524)
				(type default)
			)
			(layer "B.SilkS")
		)
		(fp_line
			(start -0.67945 -0.3048)
			(end -0.67945 0.3048)
			(stroke
				(width 0.1)
				(type default)
			)
			(layer "B.Fab")
		)
		(fp_line
			(start -0.67945 0.3048)
			(end -0.120396 0.3048)
			(stroke
				(width 0.1)
				(type default)
			)
			(layer "B.Fab")
		)
		(fp_line
			(start -0.12065 -0.3048)
			(end -0.67945 -0.3048)
			(stroke
				(width 0.1)
				(type default)
			)
			(layer "B.Fab")
		)
		(fp_line
			(start -0.12065 -0.2794)
			(end -0.12065 -0.3048)
			(stroke
				(width 0.1)
				(type default)
			)
			(layer "B.Fab")
		)
		(fp_line
			(start -0.120396 0.2794)
			(end 0.12065 0.2794)
			(stroke
				(width 0.1)
				(type default)
			)
			(layer "B.Fab")
		)
		(fp_line
			(start -0.120396 0.3048)
			(end -0.120396 0.2794)
			(stroke
				(width 0.1)
				(type default)
			)
			(layer "B.Fab")
		)
		(fp_line
			(start 0.12065 -0.305054)
			(end 0.12065 -0.2794)
			(stroke
				(width 0.1)
				(type default)
			)
			(layer "B.Fab")
		)
		(fp_line
			(start 0.12065 -0.2794)
			(end -0.12065 -0.2794)
			(stroke
				(width 0.1)
				(type default)
			)
			(layer "B.Fab")
		)
		(fp_line
			(start 0.12065 0.2794)
			(end 0.12065 0.3048)
			(stroke
				(width 0.1)
				(type default)
			)
			(layer "B.Fab")
		)
		(fp_line
			(start 0.12065 0.3048)
			(end 0.67945 0.3048)
			(stroke
				(width 0.1)
				(type default)
			)
			(layer "B.Fab")
		)
		(fp_line
			(start 0.67945 -0.305054)
			(end 0.12065 -0.305054)
			(stroke
				(width 0.1)
				(type default)
			)
			(layer "B.Fab")
		)
		(fp_line
			(start 0.67945 0.3048)
			(end 0.67945 -0.305054)
			(stroke
				(width 0.1)
				(type default)
			)
			(layer "B.Fab")
		)
		(pad "1" smd circle
			(at 0.40005 0 180)
			(size 0 0)
			(layers "B.Cu" "B.Mask" "B.Paste")
			(net "P1V8_AUX")
		)
		(pad "2" smd circle
			(at -0.40005 0 180)
			(size 0 0)
			(layers "B.Cu" "B.Mask" "B.Paste")
			(net "GND")
		)
	)
	(footprint ""
		(layer "B.Cu")
		(at 74.810112 -56.937656 -90)
		(property "Reference" "C118"
			(at 0 0 90)
			(layer "B.SilkS")
			(hide yes)
			(effects
				(font
					(size 1.27 1.27)
				)
				(justify mirror)
			)
		)
		(property "Value" ""
			(at 0 0 90)
			(layer "B.Fab")
			(effects
				(font
					(size 1.27 1.27)
				)
				(justify mirror)
			)
		)
		(duplicate_pad_numbers_are_jumpers no)
		(fp_line
			(start -1.2954 0.5842)
			(end 1.2954 0.5842)
			(stroke
				(width 0.1524)
				(type default)
			)
			(layer "B.SilkS")
		)
		(fp_line
			(start 1.2954 0.5842)
			(end 1.2954 -0.5842)
			(stroke
				(width 0.1524)
				(type default)
			)
			(layer "B.SilkS")
		)
		(fp_line
			(start -1.2954 -0.5842)
			(end -1.2954 0.5842)
			(stroke
				(width 0.1524)
				(type default)
			)
			(layer "B.SilkS")
		)
		(fp_line
			(start 0 -0.5842)
			(end 0 0.5842)
			(stroke
				(width 0.1524)
				(type default)
			)
			(layer "B.SilkS")
		)
		(fp_line
			(start 1.2954 -0.5842)
			(end -1.2954 -0.5842)
			(stroke
				(width 0.1524)
				(type default)
			)
			(layer "B.SilkS")
		)
		(fp_line
			(start -0.8636 0.4572)
			(end 0.8636 0.4572)
			(stroke
				(width 0.1)
				(type default)
			)
			(layer "B.Fab")
		)
		(fp_line
			(start 0.8636 0.4572)
			(end 0.8636 0.4064)
			(stroke
				(width 0.1)
				(type default)
			)
			(layer "B.Fab")
		)
		(fp_line
			(start -1.1938 0.4064)
			(end -0.8636 0.4064)
			(stroke
				(width 0.1)
				(type default)
			)
			(layer "B.Fab")
		)
		(fp_line
			(start -0.8636 0.4064)
			(end -0.8636 0.4572)
			(stroke
				(width 0.1)
				(type default)
			)
			(layer "B.Fab")
		)
		(fp_line
			(start 0.8636 0.4064)
			(end 1.1938 0.4064)
			(stroke
				(width 0.1)
				(type default)
			)
			(layer "B.Fab")
		)
		(fp_line
			(start 1.1938 0.4064)
			(end 1.1938 -0.4064)
			(stroke
				(width 0.1)
				(type default)
			)
			(layer "B.Fab")
		)
		(fp_line
			(start -1.1938 -0.4064)
			(end -1.1938 0.4064)
			(stroke
				(width 0.1)
				(type default)
			)
			(layer "B.Fab")
		)
		(fp_line
			(start -0.8636 -0.4064)
			(end -1.1938 -0.4064)
			(stroke
				(width 0.1)
				(type default)
			)
			(layer "B.Fab")
		)
		(fp_line
			(start 0.8636 -0.4064)
			(end 0.8636 -0.4572)
			(stroke
				(width 0.1)
				(type default)
			)
			(layer "B.Fab")
		)
		(fp_line
			(start 1.1938 -0.4064)
			(end 0.8636 -0.4064)
			(stroke
				(width 0.1)
				(type default)
			)
			(layer "B.Fab")
		)
		(fp_line
			(start -0.8636 -0.4572)
			(end -0.8636 -0.4064)
			(stroke
				(width 0.1)
				(type default)
			)
			(layer "B.Fab")
		)
		(fp_line
			(start 0.8636 -0.4572)
			(end -0.8636 -0.4572)
			(stroke
				(width 0.1)
				(type default)
			)
			(layer "B.Fab")
		)
		(pad "1" smd rect
			(at 0.7366 0 180)
			(size 0.7112 0.8128)
			(layers "B.Cu" "B.Mask" "B.Paste")
			(net "P1V0_AUX")
		)
		(pad "2" smd rect
			(at -0.7366 0 180)
			(size 0.7112 0.8128)
			(layers "B.Cu" "B.Mask" "B.Paste")
			(net "GND")
		)
	)
	(footprint ""
		(layer "B.Cu")
		(at 39.414958 -83.861656 180)
		(property "Reference" "R821"
			(at 0 0 0)
			(layer "B.SilkS")
			(hide yes)
			(effects
				(font
					(size 1.27 1.27)
				)
				(justify mirror)
			)
		)
		(property "Value" ""
			(at 0 0 0)
			(layer "B.Fab")
			(effects
				(font
					(size 1.27 1.27)
				)
				(justify mirror)
			)
		)
		(duplicate_pad_numbers_are_jumpers no)
		(fp_line
			(start 0.7874 0.4064)
			(end 0.7874 -0.4064)
			(stroke
				(width 0.1524)
				(type default)
			)
			(layer "B.SilkS")
		)
		(fp_line
			(start 0.7874 -0.4064)
			(end -0.7874 -0.4064)
			(stroke
				(width 0.1524)
				(type default)
			)
			(layer "B.SilkS")
		)
		(fp_line
			(start -0.7874 0.4064)
			(end 0.7874 0.4064)
			(stroke
				(width 0.1524)
				(type default)
			)
			(layer "B.SilkS")
		)
		(fp_line
			(start -0.7874 -0.4064)
			(end -0.7874 0.4064)
			(stroke
				(width 0.1524)
				(type default)
			)
			(layer "B.SilkS")
		)
		(fp_line
			(start 0.67945 0.3048)
			(end 0.67945 -0.305054)
			(stroke
				(width 0.1)
				(type default)
			)
			(layer "B.Fab")
		)
		(fp_line
			(start 0.67945 -0.305054)
			(end 0.12065 -0.305054)
			(stroke
				(width 0.1)
				(type default)
			)
			(layer "B.Fab")
		)
		(fp_line
			(start 0.12065 0.3048)
			(end 0.67945 0.3048)
			(stroke
				(width 0.1)
				(type default)
			)
			(layer "B.Fab")
		)
		(fp_line
			(start 0.12065 0.2794)
			(end 0.12065 0.3048)
			(stroke
				(width 0.1)
				(type default)
			)
			(layer "B.Fab")
		)
		(fp_line
			(start 0.12065 -0.2794)
			(end -0.12065 -0.2794)
			(stroke
				(width 0.1)
				(type default)
			)
			(layer "B.Fab")
		)
		(fp_line
			(start 0.12065 -0.305054)
			(end 0.12065 -0.2794)
			(stroke
				(width 0.1)
				(type default)
			)
			(layer "B.Fab")
		)
		(fp_line
			(start -0.120396 0.3048)
			(end -0.120396 0.2794)
			(stroke
				(width 0.1)
				(type default)
			)
			(layer "B.Fab")
		)
		(fp_line
			(start -0.120396 0.2794)
			(end 0.12065 0.2794)
			(stroke
				(width 0.1)
				(type default)
			)
			(layer "B.Fab")
		)
		(fp_line
			(start -0.12065 -0.2794)
			(end -0.12065 -0.3048)
			(stroke
				(width 0.1)
				(type default)
			)
			(layer "B.Fab")
		)
		(fp_line
			(start -0.12065 -0.3048)
			(end -0.67945 -0.3048)
			(stroke
				(width 0.1)
				(type default)
			)
			(layer "B.Fab")
		)
		(fp_line
			(start -0.67945 0.3048)
			(end -0.120396 0.3048)
			(stroke
				(width 0.1)
				(type default)
			)
			(layer "B.Fab")
		)
		(fp_line
			(start -0.67945 -0.3048)
			(end -0.67945 0.3048)
			(stroke
				(width 0.1)
				(type default)
			)
			(layer "B.Fab")
		)
		(pad "1" smd circle
			(at 0.40005 0)
			(size 0 0)
			(layers "B.Cu" "B.Mask" "B.Paste")
			(net "P3V3_AUX")
		)
		(pad "2" smd circle
			(at -0.40005 0)
			(size 0 0)
			(layers "B.Cu" "B.Mask" "B.Paste")
			(net "FM_BMC_ONCTL_R_N")
		)
	)
	(footprint ""
		(layer "B.Cu")
		(at 63.964058 -70.296024 180)
		(property "Reference" "R117"
			(at 0 0 0)
			(layer "B.SilkS")
			(hide yes)
			(effects
				(font
					(size 1.27 1.27)
				)
				(justify mirror)
			)
		)
		(property "Value" ""
			(at 0 0 0)
			(layer "B.Fab")
			(effects
				(font
					(size 1.27 1.27)
				)
				(justify mirror)
			)
		)
		(duplicate_pad_numbers_are_jumpers no)
		(fp_line
			(start 0.7874 0.4064)
			(end 0.7874 -0.4064)
			(stroke
				(width 0.1524)
				(type default)
			)
			(layer "B.SilkS")
		)
		(fp_line
			(start 0.7874 -0.4064)
			(end -0.7874 -0.4064)
			(stroke
				(width 0.1524)
				(type default)
			)
			(layer "B.SilkS")
		)
		(fp_line
			(start -0.7874 0.4064)
			(end 0.7874 0.4064)
			(stroke
				(width 0.1524)
				(type default)
			)
			(layer "B.SilkS")
		)
		(fp_line
			(start -0.7874 -0.4064)
			(end -0.7874 0.4064)
			(stroke
				(width 0.1524)
				(type default)
			)
			(layer "B.SilkS")
		)
		(fp_line
			(start 0.67945 0.3048)
			(end 0.67945 -0.305054)
			(stroke
				(width 0.1)
				(type default)
			)
			(layer "B.Fab")
		)
		(fp_line
			(start 0.67945 -0.305054)
			(end 0.12065 -0.305054)
			(stroke
				(width 0.1)
				(type default)
			)
			(layer "B.Fab")
		)
		(fp_line
			(start 0.12065 0.3048)
			(end 0.67945 0.3048)
			(stroke
				(width 0.1)
				(type default)
			)
			(layer "B.Fab")
		)
		(fp_line
			(start 0.12065 0.2794)
			(end 0.12065 0.3048)
			(stroke
				(width 0.1)
				(type default)
			)
			(layer "B.Fab")
		)
		(fp_line
			(start 0.12065 -0.2794)
			(end -0.12065 -0.2794)
			(stroke
				(width 0.1)
				(type default)
			)
			(layer "B.Fab")
		)
		(fp_line
			(start 0.12065 -0.305054)
			(end 0.12065 -0.2794)
			(stroke
				(width 0.1)
				(type default)
			)
			(layer "B.Fab")
		)
		(fp_line
			(start -0.120396 0.3048)
			(end -0.120396 0.2794)
			(stroke
				(width 0.1)
				(type default)
			)
			(layer "B.Fab")
		)
		(fp_line
			(start -0.120396 0.2794)
			(end 0.12065 0.2794)
			(stroke
				(width 0.1)
				(type default)
			)
			(layer "B.Fab")
		)
		(fp_line
			(start -0.12065 -0.2794)
			(end -0.12065 -0.3048)
			(stroke
				(width 0.1)
				(type default)
			)
			(layer "B.Fab")
		)
		(fp_line
			(start -0.12065 -0.3048)
			(end -0.67945 -0.3048)
			(stroke
				(width 0.1)
				(type default)
			)
			(layer "B.Fab")
		)
		(fp_line
			(start -0.67945 0.3048)
			(end -0.120396 0.3048)
			(stroke
				(width 0.1)
				(type default)
			)
			(layer "B.Fab")
		)
		(fp_line
			(start -0.67945 -0.3048)
			(end -0.67945 0.3048)
			(stroke
				(width 0.1)
				(type default)
			)
			(layer "B.Fab")
		)
		(pad "1" smd circle
			(at 0.40005 0)
			(size 0 0)
			(layers "B.Cu" "B.Mask" "B.Paste")
			(net "PGPPA_BMC_AUX")
		)
		(pad "2" smd circle
			(at -0.40005 0)
			(size 0 0)
			(layers "B.Cu" "B.Mask" "B.Paste")
			(net "RST_BMC_LPC_ESPI_N")
		)
	)
)
